#ISCELL
  mstr_misc dns *
  *
#ISCELL
  pure_quanta quanta_title_block_c *
  *
#ISCELL
  logical_power universal_gnd *
  page235_i1
#ISCELL
  logical_power universal_gnd *
  page235_i10
#CELL
  pure_quanta q_res *
  page235_i11
#ISCELL
  logical_power universal_power *
  page235_i12
#CELL
  pure_quanta conn3_210hp1030br1 *
  page235_i13
#CELL
  pure_quanta q_res *
  page235_i14
#CELL
  pure_quanta q_res *
  page235_i15
#CELL
  pure_quanta q_res *
  page235_i16
#CELL
  pure_quanta q_res *
  page235_i17
#CELL
  pure_quanta q_res *
  page235_i18
#CELL
  pure_quanta 74cbtlv3126pw *
  page235_i19
#ISCELL
  standard offpage *
  page235_i2
#ISCELL
  logical_power universal_gnd *
  page235_i20
#ISCELL
  logical_power universal_power *
  page235_i21
#ISCELL
  logical_power universal_gnd *
  page235_i22
#CELL
  pure_quanta q_cap *
  page235_i23
#CELL
  pure_quanta q_res *
  page235_i24
#CELL
  pure_quanta q_res *
  page235_i25
#CELL
  pure_quanta q_res *
  page235_i26
#CELL
  pure_quanta q_res *
  page235_i27
#ISCELL
  standard offpage *
  page235_i28
#ISCELL
  standard offpage *
  page235_i29
#CELL
  pure_quanta q_res *
  page235_i3
#ISCELL
  standard offpage *
  page235_i30
#ISCELL
  standard offpage *
  page235_i31
#CELL
  pure_quanta q_res *
  page235_i4
#ISCELL
  logical_power universal_power *
  page235_i5
#ISCELL
  standard offpage *
  page235_i6
#ISCELL
  standard offpage *
  page235_i7
#ISCELL
  standard offpage *
  page235_i8
#ISCELL
  standard offpage *
  page235_i9
